# S9S_MB_2U (Grand Teton) — schematic netlist excerpt (pin names and nets, part order shuffled) for the footprints in the layout excerpt that follows; sources: Cadence DE-HDL packaged netlist, KiCad conversion of 03242023_DA0F0TMBIJ0_F0T_Motherboard_J_brd_V01_OCP.brd

J81  PICOPROBE_BXA  DELTA-L 4.0 EMPTY  pkg TRIANG_LAUNCH_3PXB  page 308
  \1_p\  = DELTA_L_85_10INCH_TOP_DN
  \2_n\  = DELTA_L_85_10INCH_TOP_DP
  \3_g\  = DELTA_L_GND_1

(kicad_pcb
	(version 20260206)
	(generator "pcbnew")
	(generator_version "10.0")
	(general
		(thickness 1.6)
		(legacy_teardrops no)
	)
	(paper "A4")
	(title_block
		(title "03242023_DA0F0TMBIJ0_F0T_Motherboard_J_brd_V01_OCP.brd")
		(comment 1 "Grand Teton / footprints 1347-1347 of 6105")
	)
	(layers
		(0 "F.Cu" signal "TOP")
		(4 "In1.Cu" signal "GND")
		(6 "In2.Cu" signal "IN1")
		(8 "In3.Cu" signal "GND1")
		(10 "In4.Cu" signal "IN2")
		(12 "In5.Cu" signal "GND2")
		(14 "In6.Cu" signal "IN3")
		(16 "In7.Cu" signal "GND3")
		(18 "In8.Cu" signal "VCC")
		(20 "In9.Cu" signal "VCC1")
		(22 "In10.Cu" signal "GND4")
		(24 "In11.Cu" signal "IN4")
		(26 "In12.Cu" signal "GND5")
		(28 "In13.Cu" signal "IN5")
		(30 "In14.Cu" signal "GND6")
		(32 "In15.Cu" signal "IN6")
		(34 "In16.Cu" signal "GND7")
		(2 "B.Cu" signal "BOTTOM")
		(9 "F.Adhes" user "F.Adhesive")
		(11 "B.Adhes" user "B.Adhesive")
		(13 "F.Paste" user "Package Geometry/Pastemask Top")
		(15 "B.Paste" user "Package Geometry/Pastemask Bottom")
		(5 "F.SilkS" user "Ref Des/Silkscreen Top")
		(7 "B.SilkS" user "Ref Des/Silkscreen Bottom")
		(1 "F.Mask" user "Board Geometry/Soldermask Top")
		(3 "B.Mask" user "Board Geometry/Soldermask Bottom")
		(17 "Dwgs.User" user "User.Drawings")
		(19 "Cmts.User" user "User.Comments")
		(21 "Eco1.User" user "User.Eco1")
		(23 "Eco2.User" user "User.Eco2")
		(25 "Edge.Cuts" user "Board Geometry/Outline")
		(27 "Margin" user)
		(31 "F.CrtYd" user "Package Geometry/Place Bound Top")
		(29 "B.CrtYd" user "Package Geometry/Place Bound Bottom")
		(35 "F.Fab" user "Ref Des/Assembly Top")
		(33 "B.Fab" user "Ref Des/Assembly Bottom")
	)
	(footprint ""
		(layer "F.Cu")
		(at 329.240388 -4.696206 180)
		(property "Reference" "J81"
			(at -4.415282 -1.140206 90)
			(unlocked yes)
			(layer "F.SilkS")
			(effects
				(font
					(size 0.7874 0.5842)
					(thickness 0.1524)
				)
				(justify left)
			)
		)
		(property "Value" ""
			(at 0 0 180)
			(layer "F.Fab")
			(effects
				(font
					(size 1.27 1.27)
				)
			)
		)
		(duplicate_pad_numbers_are_jumpers no)
		(fp_line
			(start 1.2192 2.1082)
			(end -1.2192 2.1082)
			(stroke
				(width 0.1524)
				(type default)
			)
			(layer "F.SilkS")
		)
		(fp_line
			(start 1.2192 -2.1082)
			(end 1.2192 2.1082)
			(stroke
				(width 0.1524)
				(type default)
			)
			(layer "F.SilkS")
		)
		(fp_line
			(start -1.2192 2.1082)
			(end -1.2192 -2.1082)
			(stroke
				(width 0.1524)
				(type default)
			)
			(layer "F.SilkS")
		)
		(fp_line
			(start -1.2192 -2.1082)
			(end 1.2192 -2.1082)
			(stroke
				(width 0.1524)
				(type default)
			)
			(layer "F.SilkS")
		)
		(pad "" np_thru_hole circle
			(at -2.8829 -1.27 90)
			(size 1.0414 1.0414)
			(drill 1.0414)
			(layers "*.Cu" "*.Mask")
			(clearance 0.381)
			(thermal_gap 0.381)
		)
		(pad "" np_thru_hole circle
			(at -2.8829 1.27 90)
			(size 1.0414 1.0414)
			(drill 1.0414)
			(layers "*.Cu" "*.Mask")
			(clearance 0.381)
			(thermal_gap 0.381)
		)
		(pad "" np_thru_hole circle
			(at 3.4671 -1.27 90)
			(size 1.0414 1.0414)
			(drill 1.0414)
			(layers "*.Cu" "*.Mask")
			(clearance 0.381)
			(thermal_gap 0.381)
		)
		(pad "" np_thru_hole circle
			(at 3.4671 1.27 90)
			(size 1.0414 1.0414)
			(drill 1.0414)
			(layers "*.Cu" "*.Mask")
			(clearance 0.381)
			(thermal_gap 0.381)
		)
		(pad "1" smd rect
			(at 0.8255 -0.249936 90)
			(size 0.3048 0.508)
			(layers "F.Cu" "F.Mask" "F.Paste")
			(net "DELTA_L_85_10INCH_TOP_DN")
		)
		(pad "2" smd rect
			(at 0.8255 0.249936 90)
			(size 0.3048 0.508)
			(layers "F.Cu" "F.Mask" "F.Paste")
			(net "DELTA_L_85_10INCH_TOP_DP")
		)
		(pad "3" smd circle
			(at 0 0 180)
			(size 0 0)
			(layers "F.Cu" "F.Mask" "F.Paste")
			(net "DELTA_L_GND_1")
		)
		(zone
			(layer "F.Cu")
			(hatch none 0.5)
			(connect_pads
				(clearance 0)
			)
			(min_thickness 0.25)
			(keepout
				(tracks not_allowed)
				(vias allowed)
				(pads allowed)
				(copperpour not_allowed)
				(footprints allowed)
			)
			(placement
				(enabled no)
				(sheetname "")
			)
			(fill
				(thermal_gap 0.5)
				(thermal_bridge_width 0.5)
				(island_removal_mode 0)
			)
			(polygon
				(pts
					(xy 328.122788 -4.147566) (xy 328.122788 -4.24307) (xy 328.719688 -4.24307) (xy 328.719688 -4.64947)
					(xy 328.122788 -4.64947) (xy 328.122788 -4.742942) (xy 328.719688 -4.742942) (xy 328.719688 -5.149342)
					(xy 328.122788 -5.149342) (xy 328.122788 -5.244846) (xy 328.821288 -5.244846) (xy 328.821288 -4.147566)
				)
			)
		)
		(zone
			(layers "F.Cu" "B.Cu" "In1.Cu" "In2.Cu" "In3.Cu" "In4.Cu" "In5.Cu" "In6.Cu"
				"In7.Cu" "In8.Cu" "In9.Cu" "In10.Cu" "In11.Cu" "In12.Cu" "In13.Cu" "In14.Cu"
				"In15.Cu" "In16.Cu"
			)
			(hatch none 0.5)
			(connect_pads
				(clearance 0)
			)
			(min_thickness 0.25)
			(keepout
				(tracks not_allowed)
				(vias allowed)
				(pads allowed)
				(copperpour not_allowed)
				(footprints allowed)
			)
			(placement
				(enabled no)
				(sheetname "")
			)
			(fill
				(thermal_gap 0.5)
				(thermal_bridge_width 0.5)
				(island_removal_mode 0)
			)
			(polygon
				(pts
					(arc
						(start 326.700388 -5.966206)
						(mid 324.846188 -5.966206)
						(end 326.700388 -5.966206)
					)
				)
			)
		)
		(zone
			(layers "F.Cu" "B.Cu" "In1.Cu" "In2.Cu" "In3.Cu" "In4.Cu" "In5.Cu" "In6.Cu"
				"In7.Cu" "In8.Cu" "In9.Cu" "In10.Cu" "In11.Cu" "In12.Cu" "In13.Cu" "In14.Cu"
				"In15.Cu" "In16.Cu"
			)
			(hatch none 0.5)
			(connect_pads
				(clearance 0)
			)
			(min_thickness 0.25)
			(keepout
				(tracks not_allowed)
				(vias allowed)
				(pads allowed)
				(copperpour not_allowed)
				(footprints allowed)
			)
			(placement
				(enabled no)
				(sheetname "")
			)
			(fill
				(thermal_gap 0.5)
				(thermal_bridge_width 0.5)
				(island_removal_mode 0)
			)
			(polygon
				(pts
					(arc
						(start 326.700388 -3.426206)
						(mid 324.846188 -3.426206)
						(end 326.700388 -3.426206)
					)
				)
			)
		)
		(zone
			(layers "F.Cu" "B.Cu" "In1.Cu" "In2.Cu" "In3.Cu" "In4.Cu" "In5.Cu" "In6.Cu"
				"In7.Cu" "In8.Cu" "In9.Cu" "In10.Cu" "In11.Cu" "In12.Cu" "In13.Cu" "In14.Cu"
				"In15.Cu" "In16.Cu"
			)
			(hatch none 0.5)
			(connect_pads
				(clearance 0)
			)
			(min_thickness 0.25)
			(keepout
				(tracks not_allowed)
				(vias allowed)
				(pads allowed)
				(copperpour not_allowed)
				(footprints allowed)
			)
			(placement
				(enabled no)
				(sheetname "")
			)
			(fill
				(thermal_gap 0.5)
				(thermal_bridge_width 0.5)
				(island_removal_mode 0)
			)
			(polygon
				(pts
					(arc
						(start 333.050388 -5.966206)
						(mid 331.196188 -5.966206)
						(end 333.050388 -5.966206)
					)
				)
			)
		)
		(zone
			(layers "F.Cu" "B.Cu" "In1.Cu" "In2.Cu" "In3.Cu" "In4.Cu" "In5.Cu" "In6.Cu"
				"In7.Cu" "In8.Cu" "In9.Cu" "In10.Cu" "In11.Cu" "In12.Cu" "In13.Cu" "In14.Cu"
				"In15.Cu" "In16.Cu"
			)
			(hatch none 0.5)
			(connect_pads
				(clearance 0)
			)
			(min_thickness 0.25)
			(keepout
				(tracks not_allowed)
				(vias allowed)
				(pads allowed)
				(copperpour not_allowed)
				(footprints allowed)
			)
			(placement
				(enabled no)
				(sheetname "")
			)
			(fill
				(thermal_gap 0.5)
				(thermal_bridge_width 0.5)
				(island_removal_mode 0)
			)
			(polygon
				(pts
					(arc
						(start 333.050388 -3.426206)
						(mid 331.196188 -3.426206)
						(end 333.050388 -3.426206)
					)
				)
			)
		)
	)
)
